# T6G (Grand Teton) — schematic netlist excerpt (pin names and nets, part order shuffled) for the footprints in the layout excerpt that follows; sources: Cadence DE-HDL packaged netlist, KiCad conversion of 04192023_DAF0TMB3IC0_F0TG_MB_C_brd_V02_OCP.brd

C277  Q_CAP  22UF 4V 20% X6S  pkg C0402  page 69 : A = PVDDCR_CPU0_P0 ; B = GND
C495  Q_CAP  0.1UF 10V 10% X7S  pkg C0201  page 356 : A = P0V9_CPU1_RT3_2A ; B = GND
PC429_5  Q_CAP  22UF 16V 20% X6S  pkg C0805  page 220 : A = SW_P12V_AUX_PVDDCR_CPU1_P1_FLT ; B = GND
C628  Q_CAP  100UF 4V 20% X6S  pkg C0805  page 290 : A = P0V9_CPU0_RT1_2A ; B = GND

(kicad_pcb
	(version 20260206)
	(generator "pcbnew")
	(generator_version "10.0")
	(general
		(thickness 1.6)
		(legacy_teardrops no)
	)
	(paper "A4")
	(title_block
		(title "04192023_DAF0TMB3IC0_F0TG_MB_C_brd_V02_OCP.brd")
		(comment 1 "Grand Teton / footprints 6407-6410 of 8354")
	)
	(layers
		(0 "F.Cu" signal "TOP")
		(4 "In1.Cu" signal "GND")
		(6 "In2.Cu" signal "IN1")
		(8 "In3.Cu" signal "GND1")
		(10 "In4.Cu" signal "IN2")
		(12 "In5.Cu" signal "GND2")
		(14 "In6.Cu" signal "IN3")
		(16 "In7.Cu" signal "GND3")
		(18 "In8.Cu" signal "VCC")
		(20 "In9.Cu" signal "VCC1")
		(22 "In10.Cu" signal "GND4")
		(24 "In11.Cu" signal "IN4")
		(26 "In12.Cu" signal "GND5")
		(28 "In13.Cu" signal "IN5")
		(30 "In14.Cu" signal "GND6")
		(32 "In15.Cu" signal "IN6")
		(34 "In16.Cu" signal "GND7")
		(2 "B.Cu" signal "BOTTOM")
		(9 "F.Adhes" user "F.Adhesive")
		(11 "B.Adhes" user "B.Adhesive")
		(13 "F.Paste" user "Package Geometry/Pastemask Top")
		(15 "B.Paste" user "Package Geometry/Pastemask Bottom")
		(5 "F.SilkS" user "Ref Des/Silkscreen Top")
		(7 "B.SilkS" user "Ref Des/Silkscreen Bottom")
		(1 "F.Mask" user "Board Geometry/Soldermask Top")
		(3 "B.Mask" user "Board Geometry/Soldermask Bottom")
		(17 "Dwgs.User" user "User.Drawings")
		(19 "Cmts.User" user "User.Comments")
		(21 "Eco1.User" user "User.Eco1")
		(23 "Eco2.User" user "User.Eco2")
		(25 "Edge.Cuts" user "Board Geometry/Outline")
		(27 "Margin" user)
		(31 "F.CrtYd" user "Package Geometry/Place Bound Top")
		(29 "B.CrtYd" user "Package Geometry/Place Bound Bottom")
		(35 "F.Fab" user "Ref Des/Assembly Top")
		(33 "B.Fab" user "Ref Des/Assembly Bottom")
	)
	(footprint ""
		(layer "B.Cu")
		(at 96.575118 -338.968842 -90)
		(property "Reference" "PC429_5"
			(at 0 0 90)
			(layer "B.SilkS")
			(hide yes)
			(effects
				(font
					(size 1.27 1.27)
				)
				(justify mirror)
			)
		)
		(property "Value" ""
			(at 0 0 90)
			(layer "B.Fab")
			(effects
				(font
					(size 1.27 1.27)
				)
				(justify mirror)
			)
		)
		(duplicate_pad_numbers_are_jumpers no)
		(fp_line
			(start -1.524 0.762)
			(end 1.524 0.762)
			(stroke
				(width 0.1524)
				(type default)
			)
			(layer "B.SilkS")
		)
		(fp_line
			(start 1.524 0.762)
			(end 1.524 -0.762)
			(stroke
				(width 0.1524)
				(type default)
			)
			(layer "B.SilkS")
		)
		(fp_line
			(start -1.524 -0.762)
			(end -1.524 0.762)
			(stroke
				(width 0.1524)
				(type default)
			)
			(layer "B.SilkS")
		)
		(fp_line
			(start 1.524 -0.762)
			(end -1.524 -0.762)
			(stroke
				(width 0.1524)
				(type default)
			)
			(layer "B.SilkS")
		)
		(fp_line
			(start -1.1049 0.724916)
			(end -1.1049 -0.724916)
			(stroke
				(width 0.1)
				(type default)
			)
			(layer "B.Fab")
		)
		(fp_line
			(start 1.1049 0.724916)
			(end -1.1049 0.724916)
			(stroke
				(width 0.1)
				(type default)
			)
			(layer "B.Fab")
		)
		(fp_line
			(start -1.1049 -0.724916)
			(end 1.1049 -0.724916)
			(stroke
				(width 0.1)
				(type default)
			)
			(layer "B.Fab")
		)
		(fp_line
			(start 1.1049 -0.724916)
			(end 1.1049 0.724916)
			(stroke
				(width 0.1)
				(type default)
			)
			(layer "B.Fab")
		)
		(pad "1" smd rect
			(at 0.889 0 270)
			(size 1.016 1.27)
			(layers "B.Cu" "B.Mask" "B.Paste")
			(net "SW_P12V_AUX_PVDDCR_CPU1_P1_FLT")
		)
		(pad "2" smd rect
			(at -0.889 0 270)
			(size 1.016 1.27)
			(layers "B.Cu" "B.Mask" "B.Paste")
			(net "GND")
		)
	)
	(footprint ""
		(layer "B.Cu")
		(at 358.389174 -398.455134 180)
		(property "Reference" "C628"
			(at 0 0 0)
			(layer "B.SilkS")
			(hide yes)
			(effects
				(font
					(size 1.27 1.27)
				)
				(justify mirror)
			)
		)
		(property "Value" ""
			(at 0 0 0)
			(layer "B.Fab")
			(effects
				(font
					(size 1.27 1.27)
				)
				(justify mirror)
			)
		)
		(duplicate_pad_numbers_are_jumpers no)
		(fp_line
			(start 1.524 0.762)
			(end 1.524 -0.762)
			(stroke
				(width 0.1524)
				(type default)
			)
			(layer "B.SilkS")
		)
		(fp_line
			(start 1.524 -0.762)
			(end -1.524 -0.762)
			(stroke
				(width 0.1524)
				(type default)
			)
			(layer "B.SilkS")
		)
		(fp_line
			(start -1.524 0.762)
			(end 1.524 0.762)
			(stroke
				(width 0.1524)
				(type default)
			)
			(layer "B.SilkS")
		)
		(fp_line
			(start -1.524 -0.762)
			(end -1.524 0.762)
			(stroke
				(width 0.1524)
				(type default)
			)
			(layer "B.SilkS")
		)
		(fp_line
			(start 1.1049 0.724916)
			(end -1.1049 0.724916)
			(stroke
				(width 0.1)
				(type default)
			)
			(layer "B.Fab")
		)
		(fp_line
			(start 1.1049 -0.724916)
			(end 1.1049 0.724916)
			(stroke
				(width 0.1)
				(type default)
			)
			(layer "B.Fab")
		)
		(fp_line
			(start -1.1049 0.724916)
			(end -1.1049 -0.724916)
			(stroke
				(width 0.1)
				(type default)
			)
			(layer "B.Fab")
		)
		(fp_line
			(start -1.1049 -0.724916)
			(end 1.1049 -0.724916)
			(stroke
				(width 0.1)
				(type default)
			)
			(layer "B.Fab")
		)
		(pad "1" smd rect
			(at 0.889 0 180)
			(size 1.016 1.27)
			(layers "B.Cu" "B.Mask" "B.Paste")
			(net "P0V9_CPU0_RT1_2A")
		)
		(pad "2" smd rect
			(at -0.889 0 180)
			(size 1.016 1.27)
			(layers "B.Cu" "B.Mask" "B.Paste")
			(net "GND")
		)
	)
	(footprint ""
		(layer "B.Cu")
		(at 366.312958 -245.487952 180)
		(property "Reference" "C277"
			(at 0 0 0)
			(layer "B.SilkS")
			(hide yes)
			(effects
				(font
					(size 1.27 1.27)
				)
				(justify mirror)
			)
		)
		(property "Value" ""
			(at 0 0 0)
			(layer "B.Fab")
			(effects
				(font
					(size 1.27 1.27)
				)
				(justify mirror)
			)
		)
		(duplicate_pad_numbers_are_jumpers no)
		(fp_line
			(start 0.7874 0.4064)
			(end 0.7874 -0.4064)
			(stroke
				(width 0.1524)
				(type default)
			)
			(layer "B.SilkS")
		)
		(fp_line
			(start 0.7874 -0.4064)
			(end -0.7874 -0.4064)
			(stroke
				(width 0.1524)
				(type default)
			)
			(layer "B.SilkS")
		)
		(fp_line
			(start -0.7874 0.4064)
			(end 0.7874 0.4064)
			(stroke
				(width 0.1524)
				(type default)
			)
			(layer "B.SilkS")
		)
		(fp_line
			(start -0.7874 -0.4064)
			(end -0.7874 0.4064)
			(stroke
				(width 0.1524)
				(type default)
			)
			(layer "B.SilkS")
		)
		(fp_line
			(start 0.67945 0.3048)
			(end 0.67945 -0.305054)
			(stroke
				(width 0.1)
				(type default)
			)
			(layer "B.Fab")
		)
		(fp_line
			(start 0.67945 -0.305054)
			(end 0.12065 -0.305054)
			(stroke
				(width 0.1)
				(type default)
			)
			(layer "B.Fab")
		)
		(fp_line
			(start 0.12065 0.3048)
			(end 0.67945 0.3048)
			(stroke
				(width 0.1)
				(type default)
			)
			(layer "B.Fab")
		)
		(fp_line
			(start 0.12065 0.2794)
			(end 0.12065 0.3048)
			(stroke
				(width 0.1)
				(type default)
			)
			(layer "B.Fab")
		)
		(fp_line
			(start 0.12065 -0.2794)
			(end -0.12065 -0.2794)
			(stroke
				(width 0.1)
				(type default)
			)
			(layer "B.Fab")
		)
		(fp_line
			(start 0.12065 -0.305054)
			(end 0.12065 -0.2794)
			(stroke
				(width 0.1)
				(type default)
			)
			(layer "B.Fab")
		)
		(fp_line
			(start -0.120396 0.3048)
			(end -0.120396 0.2794)
			(stroke
				(width 0.1)
				(type default)
			)
			(layer "B.Fab")
		)
		(fp_line
			(start -0.120396 0.2794)
			(end 0.12065 0.2794)
			(stroke
				(width 0.1)
				(type default)
			)
			(layer "B.Fab")
		)
		(fp_line
			(start -0.12065 -0.2794)
			(end -0.12065 -0.3048)
			(stroke
				(width 0.1)
				(type default)
			)
			(layer "B.Fab")
		)
		(fp_line
			(start -0.12065 -0.3048)
			(end -0.67945 -0.3048)
			(stroke
				(width 0.1)
				(type default)
			)
			(layer "B.Fab")
		)
		(fp_line
			(start -0.67945 0.3048)
			(end -0.120396 0.3048)
			(stroke
				(width 0.1)
				(type default)
			)
			(layer "B.Fab")
		)
		(fp_line
			(start -0.67945 -0.3048)
			(end -0.67945 0.3048)
			(stroke
				(width 0.1)
				(type default)
			)
			(layer "B.Fab")
		)
		(pad "1" smd circle
			(at 0.40005 0)
			(size 0 0)
			(layers "B.Cu" "B.Mask" "B.Paste")
			(net "PVDDCR_CPU0_P0")
		)
		(pad "2" smd circle
			(at -0.40005 0)
			(size 0 0)
			(layers "B.Cu" "B.Mask" "B.Paste")
			(net "GND")
		)
	)
	(footprint ""
		(layer "B.Cu")
		(at 132.61848 -388.011162 -90)
		(property "Reference" "C495"
			(at 0 0 90)
			(layer "B.SilkS")
			(hide yes)
			(effects
				(font
					(size 1.27 1.27)
				)
				(justify mirror)
			)
		)
		(property "Value" ""
			(at 0 0 90)
			(layer "B.Fab")
			(effects
				(font
					(size 1.27 1.27)
				)
				(justify mirror)
			)
		)
		(duplicate_pad_numbers_are_jumpers no)
		(fp_line
			(start -0.299974 0.150114)
			(end 0.299974 0.150114)
			(stroke
				(width 0.1)
				(type default)
			)
			(layer "B.Fab")
		)
		(fp_line
			(start 0.299974 0.150114)
			(end 0.299974 -0.150114)
			(stroke
				(width 0.1)
				(type default)
			)
			(layer "B.Fab")
		)
		(fp_line
			(start -0.299974 -0.150114)
			(end -0.299974 0.150114)
			(stroke
				(width 0.1)
				(type default)
			)
			(layer "B.Fab")
		)
		(fp_line
			(start 0.299974 -0.150114)
			(end -0.299974 -0.150114)
			(stroke
				(width 0.1)
				(type default)
			)
			(layer "B.Fab")
		)
		(pad "1" smd rect
			(at 0.2667 0 90)
			(size 0.3048 0.381)
			(layers "B.Cu" "B.Mask" "B.Paste")
			(net "P0V9_CPU1_RT3_2A")
		)
		(pad "2" smd rect
			(at -0.2667 0 90)
			(size 0.3048 0.381)
			(layers "B.Cu" "B.Mask" "B.Paste")
			(net "GND")
		)
	)
)
